(kicad_pcb
	(version 20260206)
	(generator "pcbnew")
	(generator_version "10.0")
	(general
		(thickness 1.6)
		(legacy_teardrops no)
	)
	(paper "A4")
	(title_block
		(title "03242023_DA0F0TMBIJ0_F0T_Motherboard_J_brd_V01_OCP.brd")
		(comment 1 "Grand Teton / footprints 3001-3006 of 6105")
	)
	(layers
		(0 "F.Cu" signal "TOP")
		(4 "In1.Cu" signal "GND")
		(6 "In2.Cu" signal "IN1")
		(8 "In3.Cu" signal "GND1")
		(10 "In4.Cu" signal "IN2")
		(12 "In5.Cu" signal "GND2")
		(14 "In6.Cu" signal "IN3")
		(16 "In7.Cu" signal "GND3")
		(18 "In8.Cu" signal "VCC")
		(20 "In9.Cu" signal "VCC1")
		(22 "In10.Cu" signal "GND4")
		(24 "In11.Cu" signal "IN4")
		(26 "In12.Cu" signal "GND5")
		(28 "In13.Cu" signal "IN5")
		(30 "In14.Cu" signal "GND6")
		(32 "In15.Cu" signal "IN6")
		(34 "In16.Cu" signal "GND7")
		(2 "B.Cu" signal "BOTTOM")
		(9 "F.Adhes" user "F.Adhesive")
		(11 "B.Adhes" user "B.Adhesive")
		(13 "F.Paste" user "Package Geometry/Pastemask Top")
		(15 "B.Paste" user "Package Geometry/Pastemask Bottom")
		(5 "F.SilkS" user "Ref Des/Silkscreen Top")
		(7 "B.SilkS" user "Ref Des/Silkscreen Bottom")
		(1 "F.Mask" user "Board Geometry/Soldermask Top")
		(3 "B.Mask" user "Board Geometry/Soldermask Bottom")
		(17 "Dwgs.User" user "User.Drawings")
		(19 "Cmts.User" user "User.Comments")
		(21 "Eco1.User" user "User.Eco1")
		(23 "Eco2.User" user "User.Eco2")
		(25 "Edge.Cuts" user "Board Geometry/Outline")
		(27 "Margin" user)
		(31 "F.CrtYd" user "Package Geometry/Place Bound Top")
		(29 "B.CrtYd" user "Package Geometry/Place Bound Bottom")
		(35 "F.Fab" user "Ref Des/Assembly Top")
		(33 "B.Fab" user "Ref Des/Assembly Bottom")
	)
	(footprint ""
		(layer "F.Cu")
		(at 75.705462 -38.532562)
		(property "Reference" "C2012"
			(at 0 0 0)
			(layer "F.SilkS")
			(hide yes)
			(effects
				(font
					(size 1.27 1.27)
				)
			)
		)
		(property "Value" ""
			(at 0 0 0)
			(layer "F.Fab")
			(effects
				(font
					(size 1.27 1.27)
				)
			)
		)
		(duplicate_pad_numbers_are_jumpers no)
		(fp_line
			(start -0.7874 -0.4064)
			(end 0.7874 -0.4064)
			(stroke
				(width 0.1524)
				(type default)
			)
			(layer "F.SilkS")
		)
		(fp_line
			(start -0.7874 0.4064)
			(end -0.7874 -0.4064)
			(stroke
				(width 0.1524)
				(type default)
			)
			(layer "F.SilkS")
		)
		(fp_line
			(start 0.7874 -0.4064)
			(end 0.7874 0.4064)
			(stroke
				(width 0.1524)
				(type default)
			)
			(layer "F.SilkS")
		)
		(fp_line
			(start 0.7874 0.4064)
			(end -0.7874 0.4064)
			(stroke
				(width 0.1524)
				(type default)
			)
			(layer "F.SilkS")
		)
		(fp_line
			(start -0.67945 -0.305054)
			(end -0.12065 -0.305054)
			(stroke
				(width 0.1)
				(type default)
			)
			(layer "F.Fab")
		)
		(fp_line
			(start -0.67945 0.3048)
			(end -0.67945 -0.305054)
			(stroke
				(width 0.1)
				(type default)
			)
			(layer "F.Fab")
		)
		(fp_line
			(start -0.12065 -0.305054)
			(end -0.12065 -0.2794)
			(stroke
				(width 0.1)
				(type default)
			)
			(layer "F.Fab")
		)
		(fp_line
			(start -0.12065 -0.2794)
			(end 0.12065 -0.2794)
			(stroke
				(width 0.1)
				(type default)
			)
			(layer "F.Fab")
		)
		(fp_line
			(start -0.12065 0.2794)
			(end -0.12065 0.3048)
			(stroke
				(width 0.1)
				(type default)
			)
			(layer "F.Fab")
		)
		(fp_line
			(start -0.12065 0.3048)
			(end -0.67945 0.3048)
			(stroke
				(width 0.1)
				(type default)
			)
			(layer "F.Fab")
		)
		(fp_line
			(start 0.120396 0.2794)
			(end -0.12065 0.2794)
			(stroke
				(width 0.1)
				(type default)
			)
			(layer "F.Fab")
		)
		(fp_line
			(start 0.120396 0.3048)
			(end 0.120396 0.2794)
			(stroke
				(width 0.1)
				(type default)
			)
			(layer "F.Fab")
		)
		(fp_line
			(start 0.12065 -0.3048)
			(end 0.67945 -0.3048)
			(stroke
				(width 0.1)
				(type default)
			)
			(layer "F.Fab")
		)
		(fp_line
			(start 0.12065 -0.2794)
			(end 0.12065 -0.3048)
			(stroke
				(width 0.1)
				(type default)
			)
			(layer "F.Fab")
		)
		(fp_line
			(start 0.67945 -0.3048)
			(end 0.67945 0.3048)
			(stroke
				(width 0.1)
				(type default)
			)
			(layer "F.Fab")
		)
		(fp_line
			(start 0.67945 0.3048)
			(end 0.120396 0.3048)
			(stroke
				(width 0.1)
				(type default)
			)
			(layer "F.Fab")
		)
		(pad "1" smd circle
			(at -0.40005 0)
			(size 0 0)
			(layers "F.Cu" "F.Mask" "F.Paste")
			(net "P3V3_AUX")
		)
		(pad "2" smd circle
			(at 0.40005 0)
			(size 0 0)
			(layers "F.Cu" "F.Mask" "F.Paste")
			(net "GND")
		)
	)
	(footprint ""
		(layer "F.Cu")
		(at 271.966436 -398.78 90)
		(property "Reference" "PPQ8"
			(at -8.118348 -1.949196 0)
			(unlocked yes)
			(layer "F.SilkS")
			(effects
				(font
					(size 0.7874 0.5842)
					(thickness 0.1524)
				)
				(justify left)
			)
		)
		(property "Value" ""
			(at 0 0 90)
			(layer "F.Fab")
			(effects
				(font
					(size 1.27 1.27)
				)
			)
		)
		(duplicate_pad_numbers_are_jumpers no)
		(fp_line
			(start 2.350008 -2.649982)
			(end 2.350008 -2.4892)
			(stroke
				(width 0.1524)
				(type default)
			)
			(layer "F.SilkS")
		)
		(fp_line
			(start -2.350008 -2.649982)
			(end 2.350008 -2.649982)
			(stroke
				(width 0.1524)
				(type default)
			)
			(layer "F.SilkS")
		)
		(fp_line
			(start -2.350008 -2.4384)
			(end -2.350008 -2.649982)
			(stroke
				(width 0.1524)
				(type default)
			)
			(layer "F.SilkS")
		)
		(fp_line
			(start 2.350008 2.4892)
			(end 2.350008 2.649982)
			(stroke
				(width 0.1524)
				(type default)
			)
			(layer "F.SilkS")
		)
		(fp_line
			(start 2.350008 2.649982)
			(end -2.350008 2.649982)
			(stroke
				(width 0.1524)
				(type default)
			)
			(layer "F.SilkS")
		)
		(fp_line
			(start -2.350008 2.649982)
			(end -2.350008 2.413)
			(stroke
				(width 0.1524)
				(type default)
			)
			(layer "F.SilkS")
		)
		(fp_poly
			(pts
				(xy -3.717544 -1.905) (xy -4.758944 -2.3241) (xy -4.758944 -1.524)
			)
			(stroke
				(width 0)
				(type default)
			)
			(fill yes)
			(layer "F.SilkS")
		)
		(fp_line
			(start 2.350008 -2.649982)
			(end 2.350008 2.649982)
			(stroke
				(width 0.1)
				(type default)
			)
			(layer "F.Fab")
		)
		(fp_line
			(start -2.350008 -2.649982)
			(end 2.350008 -2.649982)
			(stroke
				(width 0.1)
				(type default)
			)
			(layer "F.Fab")
		)
		(fp_line
			(start 2.350008 2.649982)
			(end -2.350008 2.649982)
			(stroke
				(width 0.1)
				(type default)
			)
			(layer "F.Fab")
		)
		(fp_line
			(start -2.350008 2.649982)
			(end -2.350008 -2.649982)
			(stroke
				(width 0.1)
				(type default)
			)
			(layer "F.Fab")
		)
		(fp_poly
			(pts
				(xy -3.717544 -1.905) (xy -4.758944 -2.3241) (xy -4.758944 -1.524)
			)
			(stroke
				(width 0)
				(type default)
			)
			(fill yes)
			(layer "F.Fab")
		)
		(pad "1" smd rect
			(at -2.999994 -1.905)
			(size 0.7112 1.1684)
			(layers "F.Cu" "F.Mask" "F.Paste")
			(net "P12V_AUX")
		)
		(pad "2" smd rect
			(at -2.999994 -0.635)
			(size 0.7112 1.1684)
			(layers "F.Cu" "F.Mask" "F.Paste")
			(net "P12V_AUX")
		)
		(pad "3" smd rect
			(at -2.999994 0.635)
			(size 0.7112 1.1684)
			(layers "F.Cu" "F.Mask" "F.Paste")
			(net "P12V_AUX")
		)
		(pad "4" smd rect
			(at -2.999994 1.905)
			(size 0.7112 1.1684)
			(layers "F.Cu" "F.Mask" "F.Paste")
			(net "P12V_HSC_GATE_G4")
		)
		(pad "5" smd circle
			(at 0.925068 0)
			(size 0 0)
			(layers "F.Cu" "F.Mask" "F.Paste")
			(net "P12V_MAIN_R")
		)
		(zone
			(layer "F.Cu")
			(hatch none 0.5)
			(connect_pads
				(clearance 0)
			)
			(min_thickness 0.25)
			(keepout
				(tracks not_allowed)
				(vias allowed)
				(pads allowed)
				(copperpour not_allowed)
				(footprints allowed)
			)
			(placement
				(enabled no)
				(sheetname "")
			)
			(fill
				(thermal_gap 0.5)
				(thermal_bridge_width 0.5)
				(island_removal_mode 0)
			)
			(polygon
				(pts
					(xy 269.807436 -397.3322) (xy 274.125436 -397.3322) (xy 274.608036 -397.3322) (xy 274.608036 -396.4305)
					(xy 269.324836 -396.4305) (xy 269.324836 -397.3322)
				)
			)
		)
	)
	(footprint ""
		(layer "F.Cu")
		(at 424.204892 -391.632948 180)
		(property "Reference" "R2833"
			(at 0 0 180)
			(layer "F.SilkS")
			(hide yes)
			(effects
				(font
					(size 1.27 1.27)
				)
			)
		)
		(property "Value" ""
			(at 0 0 180)
			(layer "F.Fab")
			(effects
				(font
					(size 1.27 1.27)
				)
			)
		)
		(duplicate_pad_numbers_are_jumpers no)
		(fp_line
			(start 0.7874 0.4064)
			(end -0.7874 0.4064)
			(stroke
				(width 0.1524)
				(type default)
			)
			(layer "F.SilkS")
		)
		(fp_line
			(start 0.7874 -0.4064)
			(end 0.7874 0.4064)
			(stroke
				(width 0.1524)
				(type default)
			)
			(layer "F.SilkS")
		)
		(fp_line
			(start -0.7874 0.4064)
			(end -0.7874 -0.4064)
			(stroke
				(width 0.1524)
				(type default)
			)
			(layer "F.SilkS")
		)
		(fp_line
			(start -0.7874 -0.4064)
			(end 0.7874 -0.4064)
			(stroke
				(width 0.1524)
				(type default)
			)
			(layer "F.SilkS")
		)
		(fp_line
			(start 0.67945 0.3048)
			(end 0.120396 0.3048)
			(stroke
				(width 0.1)
				(type default)
			)
			(layer "F.Fab")
		)
		(fp_line
			(start 0.67945 -0.3048)
			(end 0.67945 0.3048)
			(stroke
				(width 0.1)
				(type default)
			)
			(layer "F.Fab")
		)
		(fp_line
			(start 0.12065 -0.2794)
			(end 0.12065 -0.3048)
			(stroke
				(width 0.1)
				(type default)
			)
			(layer "F.Fab")
		)
		(fp_line
			(start 0.12065 -0.3048)
			(end 0.67945 -0.3048)
			(stroke
				(width 0.1)
				(type default)
			)
			(layer "F.Fab")
		)
		(fp_line
			(start 0.120396 0.3048)
			(end 0.120396 0.2794)
			(stroke
				(width 0.1)
				(type default)
			)
			(layer "F.Fab")
		)
		(fp_line
			(start 0.120396 0.2794)
			(end -0.12065 0.2794)
			(stroke
				(width 0.1)
				(type default)
			)
			(layer "F.Fab")
		)
		(fp_line
			(start -0.12065 0.3048)
			(end -0.67945 0.3048)
			(stroke
				(width 0.1)
				(type default)
			)
			(layer "F.Fab")
		)
		(fp_line
			(start -0.12065 0.2794)
			(end -0.12065 0.3048)
			(stroke
				(width 0.1)
				(type default)
			)
			(layer "F.Fab")
		)
		(fp_line
			(start -0.12065 -0.2794)
			(end 0.12065 -0.2794)
			(stroke
				(width 0.1)
				(type default)
			)
			(layer "F.Fab")
		)
		(fp_line
			(start -0.12065 -0.305054)
			(end -0.12065 -0.2794)
			(stroke
				(width 0.1)
				(type default)
			)
			(layer "F.Fab")
		)
		(fp_line
			(start -0.67945 0.3048)
			(end -0.67945 -0.305054)
			(stroke
				(width 0.1)
				(type default)
			)
			(layer "F.Fab")
		)
		(fp_line
			(start -0.67945 -0.305054)
			(end -0.12065 -0.305054)
			(stroke
				(width 0.1)
				(type default)
			)
			(layer "F.Fab")
		)
		(pad "1" smd circle
			(at -0.40005 0 180)
			(size 0 0)
			(layers "F.Cu" "F.Mask" "F.Paste")
			(net "FM_SWB_BIC_READY_N")
		)
		(pad "2" smd circle
			(at 0.40005 0 180)
			(size 0 0)
			(layers "F.Cu" "F.Mask" "F.Paste")
			(net "GND")
		)
	)
	(footprint ""
		(layer "F.Cu")
		(at 131.466844 -137.114026 180)
		(property "Reference" "R536"
			(at 0 0 180)
			(layer "F.SilkS")
			(hide yes)
			(effects
				(font
					(size 1.27 1.27)
				)
			)
		)
		(property "Value" ""
			(at 0 0 180)
			(layer "F.Fab")
			(effects
				(font
					(size 1.27 1.27)
				)
			)
		)
		(duplicate_pad_numbers_are_jumpers no)
		(fp_line
			(start 0.7874 0.4064)
			(end -0.7874 0.4064)
			(stroke
				(width 0.1524)
				(type default)
			)
			(layer "F.SilkS")
		)
		(fp_line
			(start 0.7874 -0.4064)
			(end 0.7874 0.4064)
			(stroke
				(width 0.1524)
				(type default)
			)
			(layer "F.SilkS")
		)
		(fp_line
			(start -0.7874 0.4064)
			(end -0.7874 -0.4064)
			(stroke
				(width 0.1524)
				(type default)
			)
			(layer "F.SilkS")
		)
		(fp_line
			(start -0.7874 -0.4064)
			(end 0.7874 -0.4064)
			(stroke
				(width 0.1524)
				(type default)
			)
			(layer "F.SilkS")
		)
		(fp_line
			(start 0.67945 0.3048)
			(end 0.120396 0.3048)
			(stroke
				(width 0.1)
				(type default)
			)
			(layer "F.Fab")
		)
		(fp_line
			(start 0.67945 -0.3048)
			(end 0.67945 0.3048)
			(stroke
				(width 0.1)
				(type default)
			)
			(layer "F.Fab")
		)
		(fp_line
			(start 0.12065 -0.2794)
			(end 0.12065 -0.3048)
			(stroke
				(width 0.1)
				(type default)
			)
			(layer "F.Fab")
		)
		(fp_line
			(start 0.12065 -0.3048)
			(end 0.67945 -0.3048)
			(stroke
				(width 0.1)
				(type default)
			)
			(layer "F.Fab")
		)
		(fp_line
			(start 0.120396 0.3048)
			(end 0.120396 0.2794)
			(stroke
				(width 0.1)
				(type default)
			)
			(layer "F.Fab")
		)
		(fp_line
			(start 0.120396 0.2794)
			(end -0.12065 0.2794)
			(stroke
				(width 0.1)
				(type default)
			)
			(layer "F.Fab")
		)
		(fp_line
			(start -0.12065 0.3048)
			(end -0.67945 0.3048)
			(stroke
				(width 0.1)
				(type default)
			)
			(layer "F.Fab")
		)
		(fp_line
			(start -0.12065 0.2794)
			(end -0.12065 0.3048)
			(stroke
				(width 0.1)
				(type default)
			)
			(layer "F.Fab")
		)
		(fp_line
			(start -0.12065 -0.2794)
			(end 0.12065 -0.2794)
			(stroke
				(width 0.1)
				(type default)
			)
			(layer "F.Fab")
		)
		(fp_line
			(start -0.12065 -0.305054)
			(end -0.12065 -0.2794)
			(stroke
				(width 0.1)
				(type default)
			)
			(layer "F.Fab")
		)
		(fp_line
			(start -0.67945 0.3048)
			(end -0.67945 -0.305054)
			(stroke
				(width 0.1)
				(type default)
			)
			(layer "F.Fab")
		)
		(fp_line
			(start -0.67945 -0.305054)
			(end -0.12065 -0.305054)
			(stroke
				(width 0.1)
				(type default)
			)
			(layer "F.Fab")
		)
		(pad "1" smd circle
			(at -0.40005 0 180)
			(size 0 0)
			(layers "F.Cu" "F.Mask" "F.Paste")
			(net "P3V3_AUX")
		)
		(pad "2" smd circle
			(at 0.40005 0 180)
			(size 0 0)
			(layers "F.Cu" "F.Mask" "F.Paste")
			(net "PCA9548_PCIE3_ADDR2")
		)
	)
	(footprint ""
		(layer "F.Cu")
		(at 31.29788 -430.875948 180)
		(property "Reference" "R2914"
			(at 0 0 180)
			(layer "F.SilkS")
			(hide yes)
			(effects
				(font
					(size 1.27 1.27)
				)
			)
		)
		(property "Value" ""
			(at 0 0 180)
			(layer "F.Fab")
			(effects
				(font
					(size 1.27 1.27)
				)
			)
		)
		(duplicate_pad_numbers_are_jumpers no)
		(fp_line
			(start 0.7874 0.4064)
			(end -0.7874 0.4064)
			(stroke
				(width 0.1524)
				(type default)
			)
			(layer "F.SilkS")
		)
		(fp_line
			(start 0.7874 -0.4064)
			(end 0.7874 0.4064)
			(stroke
				(width 0.1524)
				(type default)
			)
			(layer "F.SilkS")
		)
		(fp_line
			(start -0.7874 0.4064)
			(end -0.7874 -0.4064)
			(stroke
				(width 0.1524)
				(type default)
			)
			(layer "F.SilkS")
		)
		(fp_line
			(start -0.7874 -0.4064)
			(end 0.7874 -0.4064)
			(stroke
				(width 0.1524)
				(type default)
			)
			(layer "F.SilkS")
		)
		(fp_line
			(start 0.67945 0.3048)
			(end 0.120396 0.3048)
			(stroke
				(width 0.1)
				(type default)
			)
			(layer "F.Fab")
		)
		(fp_line
			(start 0.67945 -0.3048)
			(end 0.67945 0.3048)
			(stroke
				(width 0.1)
				(type default)
			)
			(layer "F.Fab")
		)
		(fp_line
			(start 0.12065 -0.2794)
			(end 0.12065 -0.3048)
			(stroke
				(width 0.1)
				(type default)
			)
			(layer "F.Fab")
		)
		(fp_line
			(start 0.12065 -0.3048)
			(end 0.67945 -0.3048)
			(stroke
				(width 0.1)
				(type default)
			)
			(layer "F.Fab")
		)
		(fp_line
			(start 0.120396 0.3048)
			(end 0.120396 0.2794)
			(stroke
				(width 0.1)
				(type default)
			)
			(layer "F.Fab")
		)
		(fp_line
			(start 0.120396 0.2794)
			(end -0.12065 0.2794)
			(stroke
				(width 0.1)
				(type default)
			)
			(layer "F.Fab")
		)
		(fp_line
			(start -0.12065 0.3048)
			(end -0.67945 0.3048)
			(stroke
				(width 0.1)
				(type default)
			)
			(layer "F.Fab")
		)
		(fp_line
			(start -0.12065 0.2794)
			(end -0.12065 0.3048)
			(stroke
				(width 0.1)
				(type default)
			)
			(layer "F.Fab")
		)
		(fp_line
			(start -0.12065 -0.2794)
			(end 0.12065 -0.2794)
			(stroke
				(width 0.1)
				(type default)
			)
			(layer "F.Fab")
		)
		(fp_line
			(start -0.12065 -0.305054)
			(end -0.12065 -0.2794)
			(stroke
				(width 0.1)
				(type default)
			)
			(layer "F.Fab")
		)
		(fp_line
			(start -0.67945 0.3048)
			(end -0.67945 -0.305054)
			(stroke
				(width 0.1)
				(type default)
			)
			(layer "F.Fab")
		)
		(fp_line
			(start -0.67945 -0.305054)
			(end -0.12065 -0.305054)
			(stroke
				(width 0.1)
				(type default)
			)
			(layer "F.Fab")
		)
		(pad "1" smd circle
			(at -0.40005 0 180)
			(size 0 0)
			(layers "F.Cu" "F.Mask" "F.Paste")
			(net "P3V3_AUX")
		)
		(pad "2" smd circle
			(at 0.40005 0 180)
			(size 0 0)
			(layers "F.Cu" "F.Mask" "F.Paste")
			(net "FM_SWB_PWR_EN_R1_BUF")
		)
	)
	(footprint ""
		(layer "F.Cu")
		(at 358.425496 -338.298028 -90)
		(property "Reference" "PC1341"
			(at 0 0 270)
			(layer "F.SilkS")
			(hide yes)
			(effects
				(font
					(size 1.27 1.27)
				)
			)
		)
		(property "Value" ""
			(at 0 0 270)
			(layer "F.Fab")
			(effects
				(font
					(size 1.27 1.27)
				)
			)
		)
		(duplicate_pad_numbers_are_jumpers no)
		(fp_line
			(start -0.7874 0.4064)
			(end -0.7874 -0.4064)
			(stroke
				(width 0.1524)
				(type default)
			)
			(layer "F.SilkS")
		)
		(fp_line
			(start 0.7874 0.4064)
			(end -0.7874 0.4064)
			(stroke
				(width 0.1524)
				(type default)
			)
			(layer "F.SilkS")
		)
		(fp_line
			(start -0.7874 -0.4064)
			(end 0.7874 -0.4064)
			(stroke
				(width 0.1524)
				(type default)
			)
			(layer "F.SilkS")
		)
		(fp_line
			(start 0.7874 -0.4064)
			(end 0.7874 0.4064)
			(stroke
				(width 0.1524)
				(type default)
			)
			(layer "F.SilkS")
		)
		(fp_line
			(start -0.67945 0.3048)
			(end -0.67945 -0.305054)
			(stroke
				(width 0.1)
				(type default)
			)
			(layer "F.Fab")
		)
		(fp_line
			(start -0.12065 0.3048)
			(end -0.67945 0.3048)
			(stroke
				(width 0.1)
				(type default)
			)
			(layer "F.Fab")
		)
		(fp_line
			(start 0.120396 0.3048)
			(end 0.120396 0.2794)
			(stroke
				(width 0.1)
				(type default)
			)
			(layer "F.Fab")
		)
		(fp_line
			(start 0.67945 0.3048)
			(end 0.120396 0.3048)
			(stroke
				(width 0.1)
				(type default)
			)
			(layer "F.Fab")
		)
		(fp_line
			(start -0.12065 0.2794)
			(end -0.12065 0.3048)
			(stroke
				(width 0.1)
				(type default)
			)
			(layer "F.Fab")
		)
		(fp_line
			(start 0.120396 0.2794)
			(end -0.12065 0.2794)
			(stroke
				(width 0.1)
				(type default)
			)
			(layer "F.Fab")
		)
		(fp_line
			(start -0.12065 -0.2794)
			(end 0.12065 -0.2794)
			(stroke
				(width 0.1)
				(type default)
			)
			(layer "F.Fab")
		)
		(fp_line
			(start 0.12065 -0.2794)
			(end 0.12065 -0.3048)
			(stroke
				(width 0.1)
				(type default)
			)
			(layer "F.Fab")
		)
		(fp_line
			(start 0.12065 -0.3048)
			(end 0.67945 -0.3048)
			(stroke
				(width 0.1)
				(type default)
			)
			(layer "F.Fab")
		)
		(fp_line
			(start 0.67945 -0.3048)
			(end 0.67945 0.3048)
			(stroke
				(width 0.1)
				(type default)
			)
			(layer "F.Fab")
		)
		(fp_line
			(start -0.67945 -0.305054)
			(end -0.12065 -0.305054)
			(stroke
				(width 0.1)
				(type default)
			)
			(layer "F.Fab")
		)
		(fp_line
			(start -0.12065 -0.305054)
			(end -0.12065 -0.2794)
			(stroke
				(width 0.1)
				(type default)
			)
			(layer "F.Fab")
		)
		(pad "1" smd circle
			(at -0.40005 0 270)
			(size 0 0)
			(layers "F.Cu" "F.Mask" "F.Paste")
			(net "GND")
		)
		(pad "2" smd circle
			(at 0.40005 0 270)
			(size 0 0)
			(layers "F.Cu" "F.Mask" "F.Paste")
			(net "PVCCIN_CPU0_VREF")
		)
	)
)
